(kicad_pcb
	(version 20260206)
	(generator "pcbnew")
	(generator_version "10.0")
	(general
		(thickness 1.6)
		(legacy_teardrops no)
	)
	(paper "A4")
	(title_block
		(title "v1-chassis-manager — T6M_CM_d_v01_1031_1645.brd")
		(comment 1 "Open CloudServer (Microsoft) / footprints 1690-1699 of 2512")
	)
	(layers
		(0 "F.Cu" signal "TOP")
		(4 "In1.Cu" signal "GND1")
		(6 "In2.Cu" signal "IN1")
		(8 "In3.Cu" signal "VCC1")
		(10 "In4.Cu" signal "VCC2")
		(12 "In5.Cu" signal "GND2")
		(14 "In6.Cu" signal "IN2")
		(16 "In7.Cu" signal "IN3")
		(18 "In8.Cu" signal "GND3")
		(2 "B.Cu" signal "BOTTOM")
		(9 "F.Adhes" user "F.Adhesive")
		(11 "B.Adhes" user "B.Adhesive")
		(13 "F.Paste" user "Package Geometry/Pastemask Top")
		(15 "B.Paste" user "Package Geometry/Pastemask Bottom")
		(5 "F.SilkS" user "Ref Des/Silkscreen Top")
		(7 "B.SilkS" user "Ref Des/Silkscreen Bottom")
		(1 "F.Mask" user "Board Geometry/Soldermask Top")
		(3 "B.Mask" user "Board Geometry/Soldermask Bottom")
		(17 "Dwgs.User" user "User.Drawings")
		(19 "Cmts.User" user "User.Comments")
		(21 "Eco1.User" user "User.Eco1")
		(23 "Eco2.User" user "User.Eco2")
		(25 "Edge.Cuts" user "Board Geometry/Outline")
		(27 "Margin" user)
		(31 "F.CrtYd" user "Package Geometry/Place Bound Top")
		(29 "B.CrtYd" user "Package Geometry/Place Bound Bottom")
		(35 "F.Fab" user "Ref Des/Assembly Top")
		(33 "B.Fab" user "Ref Des/Assembly Bottom")
	)
	(footprint ""
		(layer "B.Cu")
		(at 108.478066 -132.290566 90)
		(property "Reference" "PR53"
			(at -4.308856 0.196088 270)
			(unlocked yes)
			(layer "B.SilkS")
			(effects
				(font
					(size 0.7874 0.5842)
					(thickness 0.1524)
				)
				(justify left mirror)
			)
		)
		(property "Value" ""
			(at 0 0 90)
			(layer "B.Fab")
			(effects
				(font
					(size 1.27 1.27)
				)
				(justify mirror)
			)
		)
		(duplicate_pad_numbers_are_jumpers no)
		(fp_line
			(start 0.7874 -0.4064)
			(end -0.7874 -0.4064)
			(stroke
				(width 0.1524)
				(type default)
			)
			(layer "B.SilkS")
		)
		(fp_line
			(start -0.7874 -0.4064)
			(end -0.7874 0.4064)
			(stroke
				(width 0.1524)
				(type default)
			)
			(layer "B.SilkS")
		)
		(fp_line
			(start 0.7874 0.4064)
			(end 0.7874 -0.4064)
			(stroke
				(width 0.1524)
				(type default)
			)
			(layer "B.SilkS")
		)
		(fp_line
			(start -0.7874 0.4064)
			(end 0.7874 0.4064)
			(stroke
				(width 0.1524)
				(type default)
			)
			(layer "B.SilkS")
		)
		(fp_poly
			(pts
				(xy 0.508 0.2794) (xy 0.508 0.2286) (xy 0.635 0.2286) (xy 0.635 -0.254) (xy 0.5334 -0.254) (xy 0.5334 -0.2794)
				(xy -0.5334 -0.2794) (xy -0.5334 -0.254) (xy -0.635 -0.254) (xy -0.635 0.254) (xy -0.5334 0.254)
				(xy -0.5334 0.2794)
			)
			(stroke
				(width 0)
				(type default)
			)
			(fill no)
			(layer "B.CrtYd")
		)
		(pad "1" smd rect
			(at -0.40005 0 270)
			(size 0.4572 0.508)
			(layers "B.Cu" "B.Mask" "B.Paste")
			(net "VR_PVCCP_NODE1_LGATE1")
		)
		(pad "2" smd rect
			(at 0.40005 0 270)
			(size 0.4572 0.508)
			(layers "B.Cu" "B.Mask" "B.Paste")
			(net "GND")
		)
	)
	(footprint ""
		(layer "B.Cu")
		(at 52.310538 -56.417718 180)
		(property "Reference" "C113"
			(at -1.715516 -1.493266 0)
			(unlocked yes)
			(layer "B.SilkS")
			(effects
				(font
					(size 0.7874 0.5842)
					(thickness 0.1524)
				)
				(justify left mirror)
			)
		)
		(property "Value" ""
			(at 0 0 0)
			(layer "B.Fab")
			(effects
				(font
					(size 1.27 1.27)
				)
				(justify mirror)
			)
		)
		(duplicate_pad_numbers_are_jumpers no)
		(fp_line
			(start 1.905 0.8636)
			(end 1.905 -0.8636)
			(stroke
				(width 0.1524)
				(type default)
			)
			(layer "B.SilkS")
		)
		(fp_line
			(start 1.905 -0.8636)
			(end -1.905 -0.8636)
			(stroke
				(width 0.1524)
				(type default)
			)
			(layer "B.SilkS")
		)
		(fp_line
			(start 0 0.8382)
			(end 0 -0.8382)
			(stroke
				(width 0.1524)
				(type default)
			)
			(layer "B.SilkS")
		)
		(fp_line
			(start -1.905 0.8636)
			(end 1.905 0.8636)
			(stroke
				(width 0.1524)
				(type default)
			)
			(layer "B.SilkS")
		)
		(fp_line
			(start -1.905 -0.8636)
			(end -1.905 0.8636)
			(stroke
				(width 0.1524)
				(type default)
			)
			(layer "B.SilkS")
		)
		(fp_rect
			(start 1.524 0.7366)
			(end -1.524 -0.7366)
			(stroke
				(width 0)
				(type default)
			)
			(fill no)
			(layer "B.CrtYd")
		)
		(pad "1" smd rect
			(at -0.94996 0)
			(size 1.1176 1.3716)
			(layers "B.Cu" "B.Mask" "B.Paste")
			(net "PV_VDDR_NODE1")
		)
		(pad "2" smd rect
			(at 0.94996 0)
			(size 1.1176 1.3716)
			(layers "B.Cu" "B.Mask" "B.Paste")
			(net "GND")
		)
	)
	(footprint ""
		(layer "B.Cu")
		(at 142.22476 -184.951624 -90)
		(property "Reference" "C738"
			(at -4.357624 2.170938 270)
			(unlocked yes)
			(layer "B.SilkS")
			(effects
				(font
					(size 0.7874 0.5842)
					(thickness 0.1524)
				)
				(justify left mirror)
			)
		)
		(property "Value" ""
			(at 0 0 90)
			(layer "B.Fab")
			(effects
				(font
					(size 1.27 1.27)
				)
				(justify mirror)
			)
		)
		(duplicate_pad_numbers_are_jumpers no)
		(fp_line
			(start -0.7874 0.4064)
			(end 0.7874 0.4064)
			(stroke
				(width 0.1524)
				(type default)
			)
			(layer "B.SilkS")
		)
		(fp_line
			(start 0.7874 0.4064)
			(end 0.7874 -0.4064)
			(stroke
				(width 0.1524)
				(type default)
			)
			(layer "B.SilkS")
		)
		(fp_line
			(start 0 0.381)
			(end 0 -0.381)
			(stroke
				(width 0.1524)
				(type default)
			)
			(layer "B.SilkS")
		)
		(fp_line
			(start -0.7874 -0.4064)
			(end -0.7874 0.4064)
			(stroke
				(width 0.1524)
				(type default)
			)
			(layer "B.SilkS")
		)
		(fp_line
			(start 0.7874 -0.4064)
			(end -0.7874 -0.4064)
			(stroke
				(width 0.1524)
				(type default)
			)
			(layer "B.SilkS")
		)
		(fp_poly
			(pts
				(xy 0.5334 0.254) (xy 0.635 0.254) (xy 0.635 0.2286) (xy 0.635 -0.254) (xy 0.5334 -0.254) (xy 0.5334 -0.2794)
				(xy -0.5334 -0.2794) (xy -0.5334 -0.254) (xy -0.635 -0.254) (xy -0.635 0.254) (xy -0.5334 0.254)
				(xy -0.5334 0.2794) (xy 0.508 0.2794) (xy 0.5334 0.2794)
			)
			(stroke
				(width 0)
				(type default)
			)
			(fill no)
			(layer "B.CrtYd")
		)
		(pad "1" smd rect
			(at -0.40005 0 90)
			(size 0.4572 0.508)
			(layers "B.Cu" "B.Mask" "B.Paste")
			(net "UART_T11_NODE4_RXD")
		)
		(pad "2" smd rect
			(at 0.40005 0 90)
			(size 0.4572 0.508)
			(layers "B.Cu" "B.Mask" "B.Paste")
			(net "GND")
		)
	)
	(footprint ""
		(layer "B.Cu")
		(at 73.649332 -62.6872 -90)
		(property "Reference" "PJ12"
			(at 1.76149 -3.316986 0)
			(unlocked yes)
			(layer "B.SilkS")
			(effects
				(font
					(size 0.7874 0.5842)
					(thickness 0.1524)
				)
				(justify left mirror)
			)
		)
		(property "Value" ""
			(at 0 0 90)
			(layer "B.Fab")
			(effects
				(font
					(size 1.27 1.27)
				)
				(justify mirror)
			)
		)
		(duplicate_pad_numbers_are_jumpers no)
		(fp_poly
			(pts
				(xy -0.2794 0.907796) (xy -0.254 0.907796) (xy -0.254 1.0414) (xy 0.254 1.0414) (xy 0.254 1.034796)
				(xy 0.254 0.933196) (xy 0.2794 0.933196) (xy 0.2794 -0.133604) (xy 0.254 -0.133604) (xy 0.254 -0.235204)
				(xy -0.254 -0.235204) (xy -0.254 -0.133604) (xy -0.2794 -0.133604)
			)
			(stroke
				(width 0)
				(type default)
			)
			(fill no)
			(layer "B.CrtYd")
		)
		(pad "1" smd custom
			(at 0 -0.000254 90)
			(size 0.127 0.127)
			(layers "B.Cu" "B.Mask" "B.Paste")
			(net "VSENSE_PV_VDDR_NODE1_P")
			(options
				(clearance outline)
				(anchor circle)
			)
			(primitives
				(gr_poly
					(pts
						(xy -0.127 -0.508) (xy -0.127 0.0508) (xy -0.254 0.0508) (xy -0.254 0.508) (xy 0.254 0.508) (xy 0.254 0.0508)
						(xy 0.127 0.0508) (xy 0.127 -0.508)
					)
					(width 0)
					(fill yes)
				)
			)
		)
		(pad "2" smd rect
			(at 0 0.799846)
			(size 0.4572 0.508)
			(layers "B.Cu" "B.Mask" "B.Paste")
			(net "PV_VDDR_NODE1")
		)
		(zone
			(layer "B.Cu")
			(hatch none 0.5)
			(connect_pads
				(clearance 0)
			)
			(min_thickness 0.25)
			(keepout
				(tracks allowed)
				(vias not_allowed)
				(pads allowed)
				(copperpour not_allowed)
				(footprints allowed)
			)
			(placement
				(enabled no)
				(sheetname "")
			)
			(fill
				(thermal_gap 0.5)
				(thermal_bridge_width 0.5)
				(island_removal_mode 0)
			)
			(polygon
				(pts
					(xy 72.563736 -62.3824) (xy 72.563736 -62.992) (xy 73.935336 -62.992) (xy 73.935336 -62.3824)
				)
			)
		)
	)
	(footprint ""
		(layer "B.Cu")
		(at 149.497796 -61.18733 180)
		(property "Reference" "C336"
			(at -0.981456 -1.187958 0)
			(unlocked yes)
			(layer "B.SilkS")
			(effects
				(font
					(size 0.7874 0.5842)
					(thickness 0.1524)
				)
				(justify left mirror)
			)
		)
		(property "Value" ""
			(at 0 0 0)
			(layer "B.Fab")
			(effects
				(font
					(size 1.27 1.27)
				)
				(justify mirror)
			)
		)
		(duplicate_pad_numbers_are_jumpers no)
		(fp_line
			(start 0.7874 0.4064)
			(end 0.7874 -0.4064)
			(stroke
				(width 0.1524)
				(type default)
			)
			(layer "B.SilkS")
		)
		(fp_line
			(start 0.7874 -0.4064)
			(end -0.7874 -0.4064)
			(stroke
				(width 0.1524)
				(type default)
			)
			(layer "B.SilkS")
		)
		(fp_line
			(start 0 0.381)
			(end 0 -0.381)
			(stroke
				(width 0.1524)
				(type default)
			)
			(layer "B.SilkS")
		)
		(fp_line
			(start -0.7874 0.4064)
			(end 0.7874 0.4064)
			(stroke
				(width 0.1524)
				(type default)
			)
			(layer "B.SilkS")
		)
		(fp_line
			(start -0.7874 -0.4064)
			(end -0.7874 0.4064)
			(stroke
				(width 0.1524)
				(type default)
			)
			(layer "B.SilkS")
		)
		(fp_poly
			(pts
				(xy 0.5334 0.254) (xy 0.635 0.254) (xy 0.635 0.2286) (xy 0.635 -0.254) (xy 0.5334 -0.254) (xy 0.5334 -0.2794)
				(xy -0.5334 -0.2794) (xy -0.5334 -0.254) (xy -0.635 -0.254) (xy -0.635 0.254) (xy -0.5334 0.254)
				(xy -0.5334 0.2794) (xy 0.508 0.2794) (xy 0.5334 0.2794)
			)
			(stroke
				(width 0)
				(type default)
			)
			(fill no)
			(layer "B.CrtYd")
		)
		(pad "1" smd rect
			(at -0.40005 0)
			(size 0.4572 0.508)
			(layers "B.Cu" "B.Mask" "B.Paste")
			(net "P1V0_SATA")
		)
		(pad "2" smd rect
			(at 0.40005 0)
			(size 0.4572 0.508)
			(layers "B.Cu" "B.Mask" "B.Paste")
			(net "GND")
		)
	)
	(footprint ""
		(layer "B.Cu")
		(at 128.701546 -36.115244)
		(property "Reference" "R1205"
			(at 1.320038 9.11098 0)
			(unlocked yes)
			(layer "B.SilkS")
			(effects
				(font
					(size 0.7874 0.5842)
					(thickness 0.1524)
				)
				(justify left mirror)
			)
		)
		(property "Value" ""
			(at 0 0 0)
			(layer "B.Fab")
			(effects
				(font
					(size 1.27 1.27)
				)
				(justify mirror)
			)
		)
		(duplicate_pad_numbers_are_jumpers no)
		(fp_line
			(start -0.7874 -0.4064)
			(end -0.7874 0.4064)
			(stroke
				(width 0.1524)
				(type default)
			)
			(layer "B.SilkS")
		)
		(fp_line
			(start -0.7874 0.4064)
			(end 0.7874 0.4064)
			(stroke
				(width 0.1524)
				(type default)
			)
			(layer "B.SilkS")
		)
		(fp_line
			(start 0.7874 -0.4064)
			(end -0.7874 -0.4064)
			(stroke
				(width 0.1524)
				(type default)
			)
			(layer "B.SilkS")
		)
		(fp_line
			(start 0.7874 0.4064)
			(end 0.7874 -0.4064)
			(stroke
				(width 0.1524)
				(type default)
			)
			(layer "B.SilkS")
		)
		(fp_poly
			(pts
				(xy 0.508 0.2794) (xy 0.508 0.2286) (xy 0.635 0.2286) (xy 0.635 -0.254) (xy 0.5334 -0.254) (xy 0.5334 -0.2794)
				(xy -0.5334 -0.2794) (xy -0.5334 -0.254) (xy -0.635 -0.254) (xy -0.635 0.254) (xy -0.5334 0.254)
				(xy -0.5334 0.2794)
			)
			(stroke
				(width 0)
				(type default)
			)
			(fill no)
			(layer "B.CrtYd")
		)
		(pad "1" smd rect
			(at -0.40005 0 180)
			(size 0.4572 0.508)
			(layers "B.Cu" "B.Mask" "B.Paste")
			(net "SIO_JTAG_CPLD3_TDI_R")
		)
		(pad "2" smd rect
			(at 0.40005 0 180)
			(size 0.4572 0.508)
			(layers "B.Cu" "B.Mask" "B.Paste")
			(net "SIO_JTAG_CPLD3_TDI")
		)
	)
	(footprint ""
		(layer "B.Cu")
		(at 66.53276 -185.205624 90)
		(property "Reference" "R859"
			(at 4.15163 0.094488 270)
			(unlocked yes)
			(layer "B.SilkS")
			(effects
				(font
					(size 0.7874 0.5842)
					(thickness 0.1524)
				)
				(justify left mirror)
			)
		)
		(property "Value" ""
			(at 0 0 90)
			(layer "B.Fab")
			(effects
				(font
					(size 1.27 1.27)
				)
				(justify mirror)
			)
		)
		(duplicate_pad_numbers_are_jumpers no)
		(fp_line
			(start 0.7874 -0.4064)
			(end -0.7874 -0.4064)
			(stroke
				(width 0.1524)
				(type default)
			)
			(layer "B.SilkS")
		)
		(fp_line
			(start -0.7874 -0.4064)
			(end -0.7874 0.4064)
			(stroke
				(width 0.1524)
				(type default)
			)
			(layer "B.SilkS")
		)
		(fp_line
			(start 0.7874 0.4064)
			(end 0.7874 -0.4064)
			(stroke
				(width 0.1524)
				(type default)
			)
			(layer "B.SilkS")
		)
		(fp_line
			(start -0.7874 0.4064)
			(end 0.7874 0.4064)
			(stroke
				(width 0.1524)
				(type default)
			)
			(layer "B.SilkS")
		)
		(fp_poly
			(pts
				(xy 0.508 0.2794) (xy 0.508 0.2286) (xy 0.635 0.2286) (xy 0.635 -0.254) (xy 0.5334 -0.254) (xy 0.5334 -0.2794)
				(xy -0.5334 -0.2794) (xy -0.5334 -0.254) (xy -0.635 -0.254) (xy -0.635 0.254) (xy -0.5334 0.254)
				(xy -0.5334 0.2794)
			)
			(stroke
				(width 0)
				(type default)
			)
			(fill no)
			(layer "B.CrtYd")
		)
		(pad "1" smd rect
			(at -0.40005 0 270)
			(size 0.4572 0.508)
			(layers "B.Cu" "B.Mask" "B.Paste")
			(net "T1_NODE1_EN")
		)
		(pad "2" smd rect
			(at 0.40005 0 270)
			(size 0.4572 0.508)
			(layers "B.Cu" "B.Mask" "B.Paste")
			(net "T1_NODE1_EN_R")
		)
	)
	(footprint ""
		(layer "B.Cu")
		(at 63.527686 -146.052286 90)
		(property "Reference" "L14"
			(at 1.451356 1.453896 270)
			(unlocked yes)
			(layer "B.SilkS")
			(effects
				(font
					(size 0.7874 0.5842)
					(thickness 0.1524)
				)
				(justify mirror)
			)
		)
		(property "Value" ""
			(at 0 0 90)
			(layer "B.Fab")
			(effects
				(font
					(size 1.27 1.27)
				)
				(justify mirror)
			)
		)
		(duplicate_pad_numbers_are_jumpers no)
		(fp_line
			(start 1.2954 -0.635)
			(end -1.2954 -0.635)
			(stroke
				(width 0.1524)
				(type default)
			)
			(layer "B.SilkS")
		)
		(fp_line
			(start 1.2954 -0.635)
			(end 1.2954 0.635)
			(stroke
				(width 0.1524)
				(type default)
			)
			(layer "B.SilkS")
		)
		(fp_line
			(start -1.2954 -0.635)
			(end -1.2954 0.635)
			(stroke
				(width 0.1524)
				(type default)
			)
			(layer "B.SilkS")
		)
		(fp_line
			(start 0.127 -0.5842)
			(end 0.127 0.5842)
			(stroke
				(width 0.1524)
				(type default)
			)
			(layer "B.SilkS")
		)
		(fp_line
			(start -0.127 -0.5842)
			(end -0.127 0.5842)
			(stroke
				(width 0.1524)
				(type default)
			)
			(layer "B.SilkS")
		)
		(fp_line
			(start -1.2954 0.635)
			(end 1.2954 0.635)
			(stroke
				(width 0.1524)
				(type default)
			)
			(layer "B.SilkS")
		)
		(fp_poly
			(pts
				(xy 0.9144 0.508) (xy 0.9144 0.3556) (xy 1.143 0.3556) (xy 1.143 -0.3556) (xy 0.9144 -0.3556) (xy 0.9144 -0.508)
				(xy -0.9144 -0.508) (xy -0.9144 -0.3556) (xy -1.143 -0.3556) (xy -1.143 0.3556) (xy -0.9144 0.3556)
				(xy -0.9144 0.508)
			)
			(stroke
				(width 0)
				(type default)
			)
			(fill no)
			(layer "B.CrtYd")
		)
		(pad "1" smd rect
			(at -0.7366 0 180)
			(size 0.7112 0.8128)
			(layers "B.Cu" "B.Mask" "B.Paste")
			(net "BMC_NODE1_ADCAV33")
		)
		(pad "2" smd rect
			(at 0.7366 0 180)
			(size 0.7112 0.8128)
			(layers "B.Cu" "B.Mask" "B.Paste")
			(net "P3V3_NODE1")
		)
	)
	(footprint ""
		(layer "B.Cu")
		(at 90.81262 -167.926512)
		(property "Reference" "R784"
			(at 24.609044 20.0152 0)
			(unlocked yes)
			(layer "B.SilkS")
			(effects
				(font
					(size 0.7874 0.5842)
					(thickness 0.1524)
				)
				(justify left mirror)
			)
		)
		(property "Value" ""
			(at 0 0 0)
			(layer "B.Fab")
			(effects
				(font
					(size 1.27 1.27)
				)
				(justify mirror)
			)
		)
		(duplicate_pad_numbers_are_jumpers no)
		(fp_line
			(start -0.7874 -0.4064)
			(end -0.7874 0.4064)
			(stroke
				(width 0.1524)
				(type default)
			)
			(layer "B.SilkS")
		)
		(fp_line
			(start -0.7874 0.4064)
			(end 0.7874 0.4064)
			(stroke
				(width 0.1524)
				(type default)
			)
			(layer "B.SilkS")
		)
		(fp_line
			(start 0.7874 -0.4064)
			(end -0.7874 -0.4064)
			(stroke
				(width 0.1524)
				(type default)
			)
			(layer "B.SilkS")
		)
		(fp_line
			(start 0.7874 0.4064)
			(end 0.7874 -0.4064)
			(stroke
				(width 0.1524)
				(type default)
			)
			(layer "B.SilkS")
		)
		(fp_poly
			(pts
				(xy 0.508 0.2794) (xy 0.508 0.2286) (xy 0.635 0.2286) (xy 0.635 -0.254) (xy 0.5334 -0.254) (xy 0.5334 -0.2794)
				(xy -0.5334 -0.2794) (xy -0.5334 -0.254) (xy -0.635 -0.254) (xy -0.635 0.254) (xy -0.5334 0.254)
				(xy -0.5334 0.2794)
			)
			(stroke
				(width 0)
				(type default)
			)
			(fill no)
			(layer "B.CrtYd")
		)
		(pad "1" smd rect
			(at -0.40005 0 180)
			(size 0.4572 0.508)
			(layers "B.Cu" "B.Mask" "B.Paste")
			(net "UART_SW_S0_N")
		)
		(pad "2" smd rect
			(at 0.40005 0 180)
			(size 0.4572 0.508)
			(layers "B.Cu" "B.Mask" "B.Paste")
			(net "P3V3_NODE1")
		)
	)
	(footprint ""
		(layer "B.Cu")
		(at 133.766052 -135.87095 -90)
		(property "Reference" "C930"
			(at 5.07365 -0.26797 270)
			(unlocked yes)
			(layer "B.SilkS")
			(effects
				(font
					(size 0.7874 0.5842)
					(thickness 0.1524)
				)
				(justify left mirror)
			)
		)
		(property "Value" ""
			(at 0 0 90)
			(layer "B.Fab")
			(effects
				(font
					(size 1.27 1.27)
				)
				(justify mirror)
			)
		)
		(duplicate_pad_numbers_are_jumpers no)
		(fp_line
			(start -0.7874 0.4064)
			(end 0.7874 0.4064)
			(stroke
				(width 0.1524)
				(type default)
			)
			(layer "B.SilkS")
		)
		(fp_line
			(start 0.7874 0.4064)
			(end 0.7874 -0.4064)
			(stroke
				(width 0.1524)
				(type default)
			)
			(layer "B.SilkS")
		)
		(fp_line
			(start 0 0.381)
			(end 0 -0.381)
			(stroke
				(width 0.1524)
				(type default)
			)
			(layer "B.SilkS")
		)
		(fp_line
			(start -0.7874 -0.4064)
			(end -0.7874 0.4064)
			(stroke
				(width 0.1524)
				(type default)
			)
			(layer "B.SilkS")
		)
		(fp_line
			(start 0.7874 -0.4064)
			(end -0.7874 -0.4064)
			(stroke
				(width 0.1524)
				(type default)
			)
			(layer "B.SilkS")
		)
		(fp_poly
			(pts
				(xy 0.5334 0.254) (xy 0.635 0.254) (xy 0.635 0.2286) (xy 0.635 -0.254) (xy 0.5334 -0.254) (xy 0.5334 -0.2794)
				(xy -0.5334 -0.2794) (xy -0.5334 -0.254) (xy -0.635 -0.254) (xy -0.635 0.254) (xy -0.5334 0.254)
				(xy -0.5334 0.2794) (xy 0.508 0.2794) (xy 0.5334 0.2794)
			)
			(stroke
				(width 0)
				(type default)
			)
			(fill no)
			(layer "B.CrtYd")
		)
		(pad "1" smd rect
			(at -0.40005 0 90)
			(size 0.4572 0.508)
			(layers "B.Cu" "B.Mask" "B.Paste")
			(net "P1V0_PCI_SW_A")
		)
		(pad "2" smd rect
			(at 0.40005 0 90)
			(size 0.4572 0.508)
			(layers "B.Cu" "B.Mask" "B.Paste")
			(net "GND")
		)
	)
)
